(kicad_pcb
	(version 20260206)
	(generator "pcbnew")
	(generator_version "10.0")
	(general
		(thickness 1.6)
		(legacy_teardrops no)
	)
	(paper "A4")
	(title_block
		(title "Bryce Canyon_IOM_M2_16342-2_OCP.brd")
		(comment 1 "Bryce Canyon / footprints 337-341 of 1146")
	)
	(layers
		(0 "F.Cu" signal "TOP")
		(4 "In1.Cu" signal "L2GND")
		(6 "In2.Cu" signal "L3")
		(8 "In3.Cu" signal "L4VCC")
		(10 "In4.Cu" signal "L5VCC")
		(12 "In5.Cu" signal "L6")
		(14 "In6.Cu" signal "L7GND")
		(2 "B.Cu" signal "BOTTOM")
		(9 "F.Adhes" user "F.Adhesive")
		(11 "B.Adhes" user "B.Adhesive")
		(13 "F.Paste" user "Package Geometry/Pastemask Top")
		(15 "B.Paste" user "Package Geometry/Pastemask Bottom")
		(5 "F.SilkS" user "Ref Des/Silkscreen Top")
		(7 "B.SilkS" user "Ref Des/Silkscreen Bottom")
		(1 "F.Mask" user "Board Geometry/Soldermask Top")
		(3 "B.Mask" user "Board Geometry/Soldermask Bottom")
		(17 "Dwgs.User" user "User.Drawings")
		(19 "Cmts.User" user "User.Comments")
		(21 "Eco1.User" user "User.Eco1")
		(23 "Eco2.User" user "User.Eco2")
		(25 "Edge.Cuts" user "Board Geometry/Outline")
		(27 "Margin" user)
		(31 "F.CrtYd" user "Package Geometry/Place Bound Top")
		(29 "B.CrtYd" user "Package Geometry/Place Bound Bottom")
		(35 "F.Fab" user "Ref Des/Assembly Top")
		(33 "B.Fab" user "Ref Des/Assembly Bottom")
	)
	(footprint ""
		(layer "F.Cu")
		(at 219.79382 -54.676548 -90)
		(property "Reference" "R476"
			(at 0 0 270)
			(layer "F.SilkS")
			(hide yes)
			(effects
				(font
					(size 1.27 1.27)
				)
			)
		)
		(property "Value" "866KR2F-GP"
			(at 0.064008 -3.993896 270)
			(unlocked yes)
			(layer "F.Fab")
			(hide yes)
			(effects
				(font
					(size 1.016 1.016)
					(thickness 0.1524)
				)
			)
		)
		(property "Device Type" "R402H16"
			(at 0.064008 -5.517896 270)
			(unlocked yes)
			(layer "F.Fab")
			(hide yes)
			(effects
				(font
					(size 1.016 1.016)
					(thickness 0.1524)
				)
			)
		)
		(duplicate_pad_numbers_are_jumpers no)
		(fp_line
			(start -0.508 -0.9398)
			(end -0.508 0.9398)
			(stroke
				(width 0.1524)
				(type default)
			)
			(layer "F.SilkS")
		)
		(fp_line
			(start 0.508 -0.9398)
			(end -0.508 -0.9398)
			(stroke
				(width 0.1524)
				(type default)
			)
			(layer "F.SilkS")
		)
		(fp_rect
			(start -0.508 0.9398)
			(end 0.508 -0.9398)
			(stroke
				(width 0)
				(type default)
			)
			(fill no)
			(layer "F.CrtYd")
		)
		(fp_rect
			(start -0.508 0.9398)
			(end 0.508 -0.9398)
			(stroke
				(width 0)
				(type default)
			)
			(fill no)
			(layer "F.Fab")
		)
		(pad "1" smd custom
			(at 0 -0.4445 270)
			(size 0.1397 0.1397)
			(layers "F.Cu" "F.Mask" "F.Paste")
			(net "P5V_STBY_VREG")
			(options
				(clearance outline)
				(anchor circle)
			)
			(primitives
				(gr_poly
					(pts
						(arc
							(start -0.1778 -0.2794)
							(mid -0.249642 -0.249642)
							(end -0.2794 -0.1778)
						)
						(arc
							(start -0.2794 0.1778)
							(mid -0.249642 0.249642)
							(end -0.1778 0.2794)
						)
						(arc
							(start 0.1778 0.2794)
							(mid 0.249642 0.249642)
							(end 0.2794 0.1778)
						)
						(arc
							(start 0.2794 -0.1778)
							(mid 0.249642 -0.249642)
							(end 0.1778 -0.2794)
						)
					)
					(width 0)
					(fill yes)
				)
			)
		)
		(pad "2" smd custom
			(at 0 0.4445 270)
			(size 0.1397 0.1397)
			(layers "F.Cu" "F.Mask" "F.Paste")
			(net "P5V_RF")
			(options
				(clearance outline)
				(anchor circle)
			)
			(primitives
				(gr_poly
					(pts
						(arc
							(start -0.1778 -0.2794)
							(mid -0.249642 -0.249642)
							(end -0.2794 -0.1778)
						)
						(arc
							(start -0.2794 0.1778)
							(mid -0.249642 0.249642)
							(end -0.1778 0.2794)
						)
						(arc
							(start 0.1778 0.2794)
							(mid 0.249642 0.249642)
							(end 0.2794 0.1778)
						)
						(arc
							(start 0.2794 -0.1778)
							(mid 0.249642 -0.249642)
							(end 0.1778 -0.2794)
						)
					)
					(width 0)
					(fill yes)
				)
			)
		)
	)
	(footprint ""
		(layer "F.Cu")
		(at 61.289184 -143.382492 90)
		(property "Reference" "R155"
			(at 0 0 90)
			(layer "F.SilkS")
			(hide yes)
			(effects
				(font
					(size 1.27 1.27)
				)
			)
		)
		(property "Value" "0R2J-2-GP"
			(at 0.064008 -3.993896 90)
			(unlocked yes)
			(layer "F.Fab")
			(hide yes)
			(effects
				(font
					(size 1.016 1.016)
					(thickness 0.1524)
				)
			)
		)
		(property "Device Type" "R402H16"
			(at 0.064008 -5.517896 90)
			(unlocked yes)
			(layer "F.Fab")
			(hide yes)
			(effects
				(font
					(size 1.016 1.016)
					(thickness 0.1524)
				)
			)
		)
		(duplicate_pad_numbers_are_jumpers no)
		(fp_line
			(start 0.508 -0.9398)
			(end -0.508 -0.9398)
			(stroke
				(width 0.1524)
				(type default)
			)
			(layer "F.SilkS")
		)
		(fp_line
			(start -0.508 -0.9398)
			(end -0.508 0.9398)
			(stroke
				(width 0.1524)
				(type default)
			)
			(layer "F.SilkS")
		)
		(fp_rect
			(start -0.508 0.9398)
			(end 0.508 -0.9398)
			(stroke
				(width 0)
				(type default)
			)
			(fill no)
			(layer "F.CrtYd")
		)
		(fp_rect
			(start -0.508 0.9398)
			(end 0.508 -0.9398)
			(stroke
				(width 0)
				(type default)
			)
			(fill no)
			(layer "F.Fab")
		)
		(pad "1" smd custom
			(at 0 -0.4445 90)
			(size 0.1397 0.1397)
			(layers "F.Cu" "F.Mask" "F.Paste")
			(net "BMC_SMB11_CLK")
			(options
				(clearance outline)
				(anchor circle)
			)
			(primitives
				(gr_poly
					(pts
						(arc
							(start -0.1778 -0.2794)
							(mid -0.249642 -0.249642)
							(end -0.2794 -0.1778)
						)
						(arc
							(start -0.2794 0.1778)
							(mid -0.249642 0.249642)
							(end -0.1778 0.2794)
						)
						(arc
							(start 0.1778 0.2794)
							(mid 0.249642 0.249642)
							(end 0.2794 0.1778)
						)
						(arc
							(start 0.2794 -0.1778)
							(mid 0.249642 -0.249642)
							(end 0.1778 -0.2794)
						)
					)
					(width 0)
					(fill yes)
				)
			)
		)
		(pad "2" smd custom
			(at 0 0.4445 90)
			(size 0.1397 0.1397)
			(layers "F.Cu" "F.Mask" "F.Paste")
			(net "I2C_EXP_RMT_SCL_OUT")
			(options
				(clearance outline)
				(anchor circle)
			)
			(primitives
				(gr_poly
					(pts
						(arc
							(start -0.1778 -0.2794)
							(mid -0.249642 -0.249642)
							(end -0.2794 -0.1778)
						)
						(arc
							(start -0.2794 0.1778)
							(mid -0.249642 0.249642)
							(end -0.1778 0.2794)
						)
						(arc
							(start 0.1778 0.2794)
							(mid 0.249642 0.249642)
							(end 0.2794 0.1778)
						)
						(arc
							(start 0.2794 -0.1778)
							(mid 0.249642 -0.249642)
							(end 0.1778 -0.2794)
						)
					)
					(width 0)
					(fill yes)
				)
			)
		)
	)
	(footprint ""
		(layer "F.Cu")
		(at 23.999952 -8.750046)
		(property "Reference" "PWR1"
			(at 0 0 0)
			(layer "F.SilkS")
			(hide yes)
			(effects
				(font
					(size 1.27 1.27)
				)
			)
		)
		(property "Value" "SW-TACT-4P-169-GP"
			(at -5.715 -0.8509 0)
			(unlocked yes)
			(layer "F.Fab")
			(hide yes)
			(effects
				(font
					(size 1.016 1.016)
					(thickness 0.1524)
				)
			)
		)
		(property "Device Type" "DTSA-65N-K-S-V-676-K"
			(at -5.715 -2.3749 0)
			(unlocked yes)
			(layer "F.Fab")
			(hide yes)
			(effects
				(font
					(size 1.016 1.016)
					(thickness 0.1524)
				)
			)
		)
		(duplicate_pad_numbers_are_jumpers no)
		(fp_line
			(start -4.4958 -4.2418)
			(end -2.54 -4.2418)
			(stroke
				(width 0.1524)
				(type default)
			)
			(layer "F.SilkS")
		)
		(fp_line
			(start -4.4958 -1.5367)
			(end -4.4958 -4.2418)
			(stroke
				(width 0.1524)
				(type default)
			)
			(layer "F.SilkS")
		)
		(fp_line
			(start -3.9497 -1.5367)
			(end -4.4958 -1.5367)
			(stroke
				(width 0.1524)
				(type default)
			)
			(layer "F.SilkS")
		)
		(fp_line
			(start -3.9497 3.2004)
			(end -3.9497 -1.5367)
			(stroke
				(width 0.1524)
				(type default)
			)
			(layer "F.SilkS")
		)
		(fp_line
			(start -2.54 -4.2418)
			(end -2.54 -2.0574)
			(stroke
				(width 0.1524)
				(type default)
			)
			(layer "F.SilkS")
		)
		(fp_line
			(start -2.54 -2.0574)
			(end 2.54 -2.0574)
			(stroke
				(width 0.1524)
				(type default)
			)
			(layer "F.SilkS")
		)
		(fp_line
			(start -2.0066 3.2004)
			(end -3.9497 3.2004)
			(stroke
				(width 0.1524)
				(type default)
			)
			(layer "F.SilkS")
		)
		(fp_line
			(start -2.0066 8.6106)
			(end -2.0066 3.2004)
			(stroke
				(width 0.1524)
				(type default)
			)
			(layer "F.SilkS")
		)
		(fp_line
			(start 2.0066 3.2004)
			(end 2.0066 8.6106)
			(stroke
				(width 0.1524)
				(type default)
			)
			(layer "F.SilkS")
		)
		(fp_line
			(start 2.0066 8.6106)
			(end -2.0066 8.6106)
			(stroke
				(width 0.1524)
				(type default)
			)
			(layer "F.SilkS")
		)
		(fp_line
			(start 2.54 -4.2418)
			(end 4.4958 -4.2418)
			(stroke
				(width 0.1524)
				(type default)
			)
			(layer "F.SilkS")
		)
		(fp_line
			(start 2.54 -2.0574)
			(end 2.54 -4.2418)
			(stroke
				(width 0.1524)
				(type default)
			)
			(layer "F.SilkS")
		)
		(fp_line
			(start 3.9497 -1.5367)
			(end 3.9497 3.2004)
			(stroke
				(width 0.1524)
				(type default)
			)
			(layer "F.SilkS")
		)
		(fp_line
			(start 3.9497 3.2004)
			(end 2.0066 3.2004)
			(stroke
				(width 0.1524)
				(type default)
			)
			(layer "F.SilkS")
		)
		(fp_line
			(start 4.4958 -4.2418)
			(end 4.4958 -1.5367)
			(stroke
				(width 0.1524)
				(type default)
			)
			(layer "F.SilkS")
		)
		(fp_line
			(start 4.4958 -1.5367)
			(end 3.9497 -1.5367)
			(stroke
				(width 0.1524)
				(type default)
			)
			(layer "F.SilkS")
		)
		(fp_circle
			(center -3.50012 -2.500122)
			(end -2.43332 -2.500122)
			(stroke
				(width 0.3048)
				(type default)
			)
			(fill no)
			(layer "F.SilkS")
		)
		(fp_circle
			(center -2.249932 0)
			(end -1.183132 0)
			(stroke
				(width 0.3048)
				(type default)
			)
			(fill no)
			(layer "F.SilkS")
		)
		(fp_circle
			(center 2.249932 0)
			(end 3.316732 0)
			(stroke
				(width 0.3048)
				(type default)
			)
			(fill no)
			(layer "F.SilkS")
		)
		(fp_circle
			(center 3.50012 -2.500122)
			(end 4.56692 -2.500122)
			(stroke
				(width 0.3048)
				(type default)
			)
			(fill no)
			(layer "F.SilkS")
		)
		(fp_poly
			(pts
				(xy -1.7526 8.3566) (xy -1.7526 2.9464) (xy -3.6957 2.9464) (xy -3.6957 -2.144522) (xy -4.2418 -2.144522)
				(xy -4.2418 -2.855722) (xy -3.6957 -2.855722) (xy -3.6957 -3.9878) (xy -3.302 -3.9878) (xy -3.302 -1.7907)
				(xy 3.302 -1.7907) (xy 3.302 -3.9878) (xy 3.6957 -3.9878) (xy 3.6957 -2.855722) (xy 4.2418 -2.855722)
				(xy 4.2418 -2.144522) (xy 3.6957 -2.144522) (xy 3.6957 2.9464) (xy 1.7526 2.9464) (xy 1.7526 8.3566)
			)
			(stroke
				(width 0)
				(type default)
			)
			(fill no)
			(layer "F.CrtYd")
		)
		(fp_poly
			(pts
				(xy -2.2606 8.8646) (xy -2.2606 3.4544) (xy -4.2037 3.4544) (xy -4.2037 -1.2827) (xy -4.7498 -1.2827)
				(xy -4.7498 -4.4958) (xy -2.286 -4.4958) (xy -2.286 -2.3114) (xy 2.286 -2.3114) (xy 2.286 -4.4958)
				(xy 4.7498 -4.4958) (xy 4.7498 -1.2827) (xy 4.2037 -1.2827) (xy 4.2037 -0.5588) (xy 3.695954 -0.5588)
				(xy 3.695954 -2.144268) (xy 4.2418 -2.144268) (xy 4.2418 -2.855976) (xy 3.695954 -2.855976) (xy 3.695954 -3.988054)
				(xy 3.301746 -3.988054) (xy 3.301746 -1.7907) (xy -3.301746 -1.7907) (xy -3.301746 -3.988054) (xy -3.695954 -3.988054)
				(xy -3.695954 -2.855976) (xy -4.2418 -2.855976) (xy -4.2418 -2.144268) (xy -3.695954 -2.144268)
				(xy -3.695954 2.9464) (xy -1.752854 2.9464) (xy -1.752854 8.3566) (xy 1.752854 8.3566) (xy 1.752854 2.9464)
				(xy 3.695954 2.9464) (xy 3.695954 -0.5461) (xy 4.2037 -0.5461) (xy 4.2037 3.4544) (xy 2.2606 3.4544)
				(xy 2.2606 8.8646)
			)
			(stroke
				(width 0)
				(type default)
			)
			(fill no)
			(layer "F.CrtYd")
		)
		(fp_poly
			(pts
				(xy 2.2606 8.8646) (xy -2.2606 8.8646) (xy -2.2606 3.4544) (xy -4.2037 3.4544) (xy -4.2037 -1.2827)
				(xy -4.7498 -1.2827) (xy -4.7498 -4.4958) (xy -2.286 -4.4958) (xy -2.286 -2.3114) (xy 2.286 -2.3114)
				(xy 2.286 -4.4958) (xy 4.7498 -4.4958) (xy 4.7498 -1.2827) (xy 4.2037 -1.2827) (xy 4.2037 3.4544)
				(xy 2.2606 3.4544)
			)
			(stroke
				(width 0)
				(type default)
			)
			(fill no)
			(layer "F.Fab")
		)
		(pad "1" thru_hole circle
			(at -2.249932 0)
			(size 1.4224 1.4224)
			(drill 1.016)
			(layers "*.Cu" "*.Mask")
			(remove_unused_layers no)
			(net "FP_PWR_BTN_N")
			(clearance 0.1524)
			(thermal_gap 0.1524)
		)
		(pad "2" thru_hole circle
			(at 2.249932 0)
			(size 1.4224 1.4224)
			(drill 1.016)
			(layers "*.Cu" "*.Mask")
			(remove_unused_layers no)
			(net "GND")
			(clearance 0.1524)
			(thermal_gap 0.1524)
		)
		(pad "3" thru_hole circle
			(at -3.50012 -2.500122)
			(size 1.4224 1.4224)
			(drill 1.016)
			(layers "*.Cu" "*.Mask")
			(remove_unused_layers no)
			(net "PWR_BTN_GND")
			(clearance 0.1524)
			(thermal_gap 0.1524)
		)
		(pad "4" thru_hole circle
			(at 3.50012 -2.500122)
			(size 1.4224 1.4224)
			(drill 1.016)
			(layers "*.Cu" "*.Mask")
			(remove_unused_layers no)
			(net "PWR_BTN_GND")
			(clearance 0.1524)
			(thermal_gap 0.1524)
		)
	)
	(footprint ""
		(layer "F.Cu")
		(at 72.4662 -135.89 90)
		(property "Reference" "R98"
			(at 0 0 90)
			(layer "F.SilkS")
			(hide yes)
			(effects
				(font
					(size 1.27 1.27)
				)
			)
		)
		(property "Value" "0R2J-2-GP"
			(at 0.064008 -3.993896 90)
			(unlocked yes)
			(layer "F.Fab")
			(hide yes)
			(effects
				(font
					(size 1.016 1.016)
					(thickness 0.1524)
				)
			)
		)
		(property "Device Type" "R402H16"
			(at 0.064008 -5.517896 90)
			(unlocked yes)
			(layer "F.Fab")
			(hide yes)
			(effects
				(font
					(size 1.016 1.016)
					(thickness 0.1524)
				)
			)
		)
		(duplicate_pad_numbers_are_jumpers no)
		(fp_line
			(start 0.508 -0.9398)
			(end -0.508 -0.9398)
			(stroke
				(width 0.1524)
				(type default)
			)
			(layer "F.SilkS")
		)
		(fp_line
			(start -0.508 -0.9398)
			(end -0.508 0.9398)
			(stroke
				(width 0.1524)
				(type default)
			)
			(layer "F.SilkS")
		)
		(fp_rect
			(start -0.508 0.9398)
			(end 0.508 -0.9398)
			(stroke
				(width 0)
				(type default)
			)
			(fill no)
			(layer "F.CrtYd")
		)
		(fp_rect
			(start -0.508 0.9398)
			(end 0.508 -0.9398)
			(stroke
				(width 0)
				(type default)
			)
			(fill no)
			(layer "F.Fab")
		)
		(pad "1" smd custom
			(at 0 -0.4445 90)
			(size 0.1397 0.1397)
			(layers "F.Cu" "F.Mask" "F.Paste")
			(net "UART_SEL_MUX")
			(options
				(clearance outline)
				(anchor circle)
			)
			(primitives
				(gr_poly
					(pts
						(arc
							(start -0.1778 -0.2794)
							(mid -0.249642 -0.249642)
							(end -0.2794 -0.1778)
						)
						(arc
							(start -0.2794 0.1778)
							(mid -0.249642 0.249642)
							(end -0.1778 0.2794)
						)
						(arc
							(start 0.1778 0.2794)
							(mid 0.249642 0.249642)
							(end 0.2794 0.1778)
						)
						(arc
							(start 0.2794 -0.1778)
							(mid 0.249642 -0.249642)
							(end 0.1778 -0.2794)
						)
					)
					(width 0)
					(fill yes)
				)
			)
		)
		(pad "2" smd custom
			(at 0 0.4445 90)
			(size 0.1397 0.1397)
			(layers "F.Cu" "F.Mask" "F.Paste")
			(net "D_FLIP_Q")
			(options
				(clearance outline)
				(anchor circle)
			)
			(primitives
				(gr_poly
					(pts
						(arc
							(start -0.1778 -0.2794)
							(mid -0.249642 -0.249642)
							(end -0.2794 -0.1778)
						)
						(arc
							(start -0.2794 0.1778)
							(mid -0.249642 0.249642)
							(end -0.1778 0.2794)
						)
						(arc
							(start 0.1778 0.2794)
							(mid 0.249642 0.249642)
							(end 0.2794 0.1778)
						)
						(arc
							(start 0.2794 -0.1778)
							(mid 0.249642 -0.249642)
							(end 0.1778 -0.2794)
						)
					)
					(width 0)
					(fill yes)
				)
			)
		)
	)
	(footprint ""
		(layer "F.Cu")
		(at 124.841 -9.652 90)
		(property "Reference" "C130"
			(at 0 0 90)
			(layer "F.SilkS")
			(hide yes)
			(effects
				(font
					(size 1.27 1.27)
				)
			)
		)
		(property "Value" "SCD1U16V2KX-3GP"
			(at 1.1811 -2.7051 90)
			(unlocked yes)
			(layer "F.Fab")
			(hide yes)
			(effects
				(font
					(size 1.016 1.016)
					(thickness 0.1524)
				)
			)
		)
		(property "Device Type" "C402H22"
			(at 1.1811 -4.2291 90)
			(unlocked yes)
			(layer "F.Fab")
			(hide yes)
			(effects
				(font
					(size 1.016 1.016)
					(thickness 0.1524)
				)
			)
		)
		(duplicate_pad_numbers_are_jumpers no)
		(fp_rect
			(start -0.4318 0.9525)
			(end 0.4318 -0.9525)
			(stroke
				(width 0)
				(type default)
			)
			(fill no)
			(layer "F.CrtYd")
		)
		(fp_rect
			(start -0.4318 0.9525)
			(end 0.4318 -0.9525)
			(stroke
				(width 0)
				(type default)
			)
			(fill no)
			(layer "F.Fab")
		)
		(pad "1" smd custom
			(at 0 -0.4445 90)
			(size 0.1524 0.1524)
			(layers "F.Cu" "F.Mask" "F.Paste")
			(net "MB0_CM_VOUT_R")
			(options
				(clearance outline)
				(anchor circle)
			)
			(primitives
				(gr_poly
					(pts
						(arc
							(start 0.3048 -0.2032)
							(mid 0.275042 -0.275042)
							(end 0.2032 -0.3048)
						)
						(arc
							(start -0.2032 -0.3048)
							(mid -0.275042 -0.275042)
							(end -0.3048 -0.2032)
						)
						(arc
							(start -0.3048 0.2032)
							(mid -0.275042 0.275042)
							(end -0.2032 0.3048)
						)
						(arc
							(start 0.2032 0.3048)
							(mid 0.275042 0.275042)
							(end 0.3048 0.2032)
						)
					)
					(width 0)
					(fill yes)
				)
			)
		)
		(pad "2" smd custom
			(at 0 0.4445 90)
			(size 0.1524 0.1524)
			(layers "F.Cu" "F.Mask" "F.Paste")
			(net "AGND_CURRENT_MON")
			(options
				(clearance outline)
				(anchor circle)
			)
			(primitives
				(gr_poly
					(pts
						(arc
							(start 0.3048 -0.2032)
							(mid 0.275042 -0.275042)
							(end 0.2032 -0.3048)
						)
						(arc
							(start -0.2032 -0.3048)
							(mid -0.275042 -0.275042)
							(end -0.3048 -0.2032)
						)
						(arc
							(start -0.3048 0.2032)
							(mid -0.275042 0.275042)
							(end -0.2032 0.3048)
						)
						(arc
							(start 0.2032 0.3048)
							(mid 0.275042 0.275042)
							(end 0.3048 0.2032)
						)
					)
					(width 0)
					(fill yes)
				)
			)
		)
	)
)
